(kicad_pcb
	(version 20260206)
	(generator "pcbnew")
	(generator_version "10.0")
	(general
		(thickness 1.6)
		(legacy_teardrops no)
	)
	(paper "A4")
	(title_block
		(title "Wiwynn_Tioga_Pass_MB.brd")
		(comment 1 "Tioga Pass / footprints 3566-3572 of 4770")
	)
	(layers
		(0 "F.Cu" signal "TOP")
		(4 "In1.Cu" signal "L2GND")
		(6 "In2.Cu" signal "L3")
		(8 "In3.Cu" signal "L4GND")
		(10 "In4.Cu" signal "L5")
		(12 "In5.Cu" signal "L6GND")
		(14 "In6.Cu" signal "L7VCC")
		(16 "In7.Cu" signal "L8VCC")
		(18 "In8.Cu" signal "L9GND")
		(20 "In9.Cu" signal "L10")
		(22 "In10.Cu" signal "L11GND")
		(24 "In11.Cu" signal "L12")
		(26 "In12.Cu" signal "L13GND")
		(2 "B.Cu" signal "BOTTOM")
		(9 "F.Adhes" user "F.Adhesive")
		(11 "B.Adhes" user "B.Adhesive")
		(13 "F.Paste" user "Package Geometry/Pastemask Top")
		(15 "B.Paste" user "Package Geometry/Pastemask Bottom")
		(5 "F.SilkS" user "Ref Des/Silkscreen Top")
		(7 "B.SilkS" user "Ref Des/Silkscreen Bottom")
		(1 "F.Mask" user "Board Geometry/Soldermask Top")
		(3 "B.Mask" user "Board Geometry/Soldermask Bottom")
		(17 "Dwgs.User" user "User.Drawings")
		(19 "Cmts.User" user "User.Comments")
		(21 "Eco1.User" user "User.Eco1")
		(23 "Eco2.User" user "User.Eco2")
		(25 "Edge.Cuts" user "Board Geometry/Outline")
		(27 "Margin" user)
		(31 "F.CrtYd" user "Package Geometry/Place Bound Top")
		(29 "B.CrtYd" user "Package Geometry/Place Bound Bottom")
		(35 "F.Fab" user "Ref Des/Assembly Top")
		(33 "B.Fab" user "Ref Des/Assembly Bottom")
	)
	(footprint ""
		(layer "B.Cu")
		(at 351.536 -34.798 -90)
		(property "Reference" "C3T3"
			(at 3.45567 5.207 0)
			(unlocked yes)
			(layer "B.SilkS")
			(effects
				(font
					(size 0.7874 0.5842)
					(thickness 0.1524)
				)
				(justify mirror)
			)
		)
		(property "Value" ""
			(at 0 0 90)
			(layer "B.Fab")
			(effects
				(font
					(size 1.27 1.27)
				)
				(justify mirror)
			)
		)
		(duplicate_pad_numbers_are_jumpers no)
		(fp_line
			(start -2.286 7.366)
			(end -1.600708 7.366)
			(stroke
				(width 0.1524)
				(type default)
			)
			(layer "B.SilkS")
		)
		(fp_line
			(start -2.286 7.366)
			(end -2.286 1.63195)
			(stroke
				(width 0.1524)
				(type default)
			)
			(layer "B.SilkS")
		)
		(fp_line
			(start 2.286 7.366)
			(end 1.60147 7.366)
			(stroke
				(width 0.1524)
				(type default)
			)
			(layer "B.SilkS")
		)
		(fp_line
			(start 2.286 7.366)
			(end 2.286 1.632712)
			(stroke
				(width 0.1524)
				(type default)
			)
			(layer "B.SilkS")
		)
		(fp_line
			(start -2.504948 1.633728)
			(end -1.6002 1.633728)
			(stroke
				(width 0.1524)
				(type default)
			)
			(layer "B.SilkS")
		)
		(fp_line
			(start 2.563114 1.633728)
			(end 1.6002 1.633728)
			(stroke
				(width 0.1524)
				(type default)
			)
			(layer "B.SilkS")
		)
		(fp_line
			(start -2.504948 -1.616456)
			(end -2.504948 1.633728)
			(stroke
				(width 0.1524)
				(type default)
			)
			(layer "B.SilkS")
		)
		(fp_line
			(start -1.6002 -1.616456)
			(end -2.504948 -1.616456)
			(stroke
				(width 0.1524)
				(type default)
			)
			(layer "B.SilkS")
		)
		(fp_line
			(start 1.6002 -1.616456)
			(end 2.563114 -1.616456)
			(stroke
				(width 0.1524)
				(type default)
			)
			(layer "B.SilkS")
		)
		(fp_line
			(start 2.563114 -1.616456)
			(end 2.563114 1.633728)
			(stroke
				(width 0.1524)
				(type default)
			)
			(layer "B.SilkS")
		)
		(fp_rect
			(start 2.286 7.366)
			(end -2.286 -0.254)
			(stroke
				(width 0)
				(type default)
			)
			(fill no)
			(layer "B.CrtYd")
		)
		(fp_line
			(start -2.286 7.366)
			(end 2.286 7.366)
			(stroke
				(width 0.1)
				(type default)
			)
			(layer "B.Fab")
		)
		(fp_line
			(start 2.286 7.366)
			(end 2.286 -0.254)
			(stroke
				(width 0.1)
				(type default)
			)
			(layer "B.Fab")
		)
		(fp_line
			(start -2.286 -0.254)
			(end -2.286 7.366)
			(stroke
				(width 0.1)
				(type default)
			)
			(layer "B.Fab")
		)
		(fp_line
			(start 2.286 -0.254)
			(end -2.286 -0.254)
			(stroke
				(width 0.1)
				(type default)
			)
			(layer "B.Fab")
		)
		(pad "1" smd rect
			(at 0 0 90)
			(size 2.54 3.048)
			(layers "B.Cu" "B.Mask" "B.Paste")
			(net "P12V_STBY")
		)
		(pad "2" smd rect
			(at 0 7.112 90)
			(size 2.54 3.048)
			(layers "B.Cu" "B.Mask" "B.Paste")
			(net "GND")
		)
	)
	(footprint ""
		(layer "B.Cu")
		(at 456.7936 -142.9004)
		(property "Reference" "R1L29"
			(at 0 0 0)
			(layer "B.SilkS")
			(hide yes)
			(effects
				(font
					(size 1.27 1.27)
				)
				(justify mirror)
			)
		)
		(property "Value" ""
			(at 0 0 0)
			(layer "B.Fab")
			(effects
				(font
					(size 1.27 1.27)
				)
				(justify mirror)
			)
		)
		(duplicate_pad_numbers_are_jumpers no)
		(fp_poly
			(pts
				(xy 0.2794 -0.1016) (xy -0.2794 -0.1016) (xy -0.2794 0.9906) (xy 0.2794 0.9906)
			)
			(stroke
				(width 0)
				(type default)
			)
			(fill no)
			(layer "B.CrtYd")
		)
		(fp_line
			(start -0.2794 -0.1016)
			(end 0.2794 -0.1016)
			(stroke
				(width 0.1)
				(type default)
			)
			(layer "B.Fab")
		)
		(fp_line
			(start -0.2794 0.9906)
			(end -0.2794 -0.1016)
			(stroke
				(width 0.1)
				(type default)
			)
			(layer "B.Fab")
		)
		(fp_line
			(start 0.2794 -0.1016)
			(end 0.2794 0.9906)
			(stroke
				(width 0.1)
				(type default)
			)
			(layer "B.Fab")
		)
		(fp_line
			(start 0.2794 0.9906)
			(end -0.2794 0.9906)
			(stroke
				(width 0.1)
				(type default)
			)
			(layer "B.Fab")
		)
		(pad "1" smd rect
			(at 0 0 180)
			(size 0.508 0.508)
			(layers "B.Cu" "B.Mask" "B.Paste")
			(net "FM_DEBUG_RST_BTN_R1_N")
		)
		(pad "2" smd rect
			(at 0 0.889 180)
			(size 0.508 0.508)
			(layers "B.Cu" "B.Mask" "B.Paste")
			(net "FM_DEBUG_RST_BTN_N")
		)
		(zone
			(layer "B.Cu")
			(hatch none 0.5)
			(connect_pads
				(clearance 0)
			)
			(min_thickness 0.25)
			(keepout
				(tracks allowed)
				(vias not_allowed)
				(pads allowed)
				(copperpour not_allowed)
				(footprints allowed)
			)
			(placement
				(enabled no)
				(sheetname "")
			)
			(fill
				(thermal_gap 0.5)
				(thermal_bridge_width 0.5)
				(island_removal_mode 0)
			)
			(polygon
				(pts
					(xy 457.0476 -142.6464) (xy 456.5396 -142.6464) (xy 456.5396 -142.2654) (xy 457.0476 -142.2654)
				)
			)
		)
		(zone
			(layer "B.Cu")
			(hatch none 0.5)
			(connect_pads
				(clearance 0)
			)
			(min_thickness 0.25)
			(keepout
				(tracks not_allowed)
				(vias allowed)
				(pads allowed)
				(copperpour not_allowed)
				(footprints allowed)
			)
			(placement
				(enabled no)
				(sheetname "")
			)
			(fill
				(thermal_gap 0.5)
				(thermal_bridge_width 0.5)
				(island_removal_mode 0)
			)
			(polygon
				(pts
					(xy 457.0476 -142.2654) (xy 456.5396 -142.2654) (xy 456.5396 -142.6464) (xy 457.0476 -142.6464)
				)
			)
		)
	)
	(footprint ""
		(layer "B.Cu")
		(at 252.1585 -145.0086 -90)
		(property "Reference" "C5L11"
			(at -1.848866 0.752348 270)
			(unlocked yes)
			(layer "B.SilkS")
			(effects
				(font
					(size 1.27 0.9652)
					(thickness 0.1524)
				)
				(justify mirror)
			)
		)
		(property "Value" ""
			(at 0 0 90)
			(layer "B.Fab")
			(effects
				(font
					(size 1.27 1.27)
				)
				(justify mirror)
			)
		)
		(duplicate_pad_numbers_are_jumpers no)
		(fp_rect
			(start 0.500126 1.598422)
			(end -0.500126 -0.201422)
			(stroke
				(width 0)
				(type default)
			)
			(fill no)
			(layer "B.CrtYd")
		)
		(fp_line
			(start -0.500126 1.598422)
			(end 0.500126 1.598422)
			(stroke
				(width 0.1)
				(type default)
			)
			(layer "B.Fab")
		)
		(fp_line
			(start 0.500126 1.598422)
			(end 0.500126 -0.201422)
			(stroke
				(width 0.1)
				(type default)
			)
			(layer "B.Fab")
		)
		(fp_line
			(start -0.500126 -0.201422)
			(end -0.500126 1.598422)
			(stroke
				(width 0.1)
				(type default)
			)
			(layer "B.Fab")
		)
		(fp_line
			(start 0.500126 -0.201422)
			(end -0.500126 -0.201422)
			(stroke
				(width 0.1)
				(type default)
			)
			(layer "B.Fab")
		)
		(pad "1" smd rect
			(at 0 0 180)
			(size 0.889 0.9906)
			(layers "B.Cu" "B.Mask" "B.Paste")
			(net "PVDDQ_DEF")
		)
		(pad "2" smd rect
			(at 0 1.397 180)
			(size 0.889 0.9906)
			(layers "B.Cu" "B.Mask" "B.Paste")
			(net "GND")
		)
		(zone
			(layer "B.Cu")
			(hatch none 0.5)
			(connect_pads
				(clearance 0)
			)
			(min_thickness 0.25)
			(keepout
				(tracks allowed)
				(vias not_allowed)
				(pads allowed)
				(copperpour not_allowed)
				(footprints allowed)
			)
			(placement
				(enabled no)
				(sheetname "")
			)
			(fill
				(thermal_gap 0.5)
				(thermal_bridge_width 0.5)
				(island_removal_mode 0)
			)
			(polygon
				(pts
					(xy 251.206 -144.5133) (xy 251.714 -144.5133) (xy 251.714 -145.5039) (xy 251.206 -145.5039)
				)
			)
		)
		(zone
			(layer "B.Cu")
			(hatch none 0.5)
			(connect_pads
				(clearance 0)
			)
			(min_thickness 0.25)
			(keepout
				(tracks not_allowed)
				(vias allowed)
				(pads allowed)
				(copperpour not_allowed)
				(footprints allowed)
			)
			(placement
				(enabled no)
				(sheetname "")
			)
			(fill
				(thermal_gap 0.5)
				(thermal_bridge_width 0.5)
				(island_removal_mode 0)
			)
			(polygon
				(pts
					(xy 251.206 -144.5133) (xy 251.714 -144.5133) (xy 251.714 -145.5039) (xy 251.206 -145.5039)
				)
			)
		)
	)
	(footprint ""
		(layer "B.Cu")
		(at 447.157094 -23.642574 -90)
		(property "Reference" "R8W5"
			(at 0.8382 -0.67818 270)
			(unlocked yes)
			(layer "B.SilkS")
			(effects
				(font
					(size 0.4064 0.254)
					(thickness 0.1524)
				)
				(justify left mirror)
			)
		)
		(property "Value" ""
			(at 0 0 90)
			(layer "B.Fab")
			(effects
				(font
					(size 1.27 1.27)
				)
				(justify mirror)
			)
		)
		(duplicate_pad_numbers_are_jumpers no)
		(fp_poly
			(pts
				(xy 0.2794 -0.1016) (xy -0.2794 -0.1016) (xy -0.2794 0.9906) (xy 0.2794 0.9906)
			)
			(stroke
				(width 0)
				(type default)
			)
			(fill no)
			(layer "B.CrtYd")
		)
		(fp_line
			(start -0.2794 0.9906)
			(end -0.2794 -0.1016)
			(stroke
				(width 0.1)
				(type default)
			)
			(layer "B.Fab")
		)
		(fp_line
			(start 0.2794 0.9906)
			(end -0.2794 0.9906)
			(stroke
				(width 0.1)
				(type default)
			)
			(layer "B.Fab")
		)
		(fp_line
			(start -0.2794 -0.1016)
			(end 0.2794 -0.1016)
			(stroke
				(width 0.1)
				(type default)
			)
			(layer "B.Fab")
		)
		(fp_line
			(start 0.2794 -0.1016)
			(end 0.2794 0.9906)
			(stroke
				(width 0.1)
				(type default)
			)
			(layer "B.Fab")
		)
		(pad "1" smd rect
			(at 0 0 90)
			(size 0.508 0.508)
			(layers "B.Cu" "B.Mask" "B.Paste")
			(net "SMB_HOST_STBY_LVC3_SCL")
		)
		(pad "2" smd rect
			(at 0 0.889 90)
			(size 0.508 0.508)
			(layers "B.Cu" "B.Mask" "B.Paste")
			(net "SMB_HOST_STBY_LVC3_SCL_R5")
		)
		(zone
			(layer "B.Cu")
			(hatch none 0.5)
			(connect_pads
				(clearance 0)
			)
			(min_thickness 0.25)
			(keepout
				(tracks not_allowed)
				(vias allowed)
				(pads allowed)
				(copperpour not_allowed)
				(footprints allowed)
			)
			(placement
				(enabled no)
				(sheetname "")
			)
			(fill
				(thermal_gap 0.5)
				(thermal_bridge_width 0.5)
				(island_removal_mode 0)
			)
			(polygon
				(pts
					(xy 446.522094 -23.388574) (xy 446.522094 -23.896574) (xy 446.903094 -23.896574) (xy 446.903094 -23.388574)
				)
			)
		)
		(zone
			(layer "B.Cu")
			(hatch none 0.5)
			(connect_pads
				(clearance 0)
			)
			(min_thickness 0.25)
			(keepout
				(tracks allowed)
				(vias not_allowed)
				(pads allowed)
				(copperpour not_allowed)
				(footprints allowed)
			)
			(placement
				(enabled no)
				(sheetname "")
			)
			(fill
				(thermal_gap 0.5)
				(thermal_bridge_width 0.5)
				(island_removal_mode 0)
			)
			(polygon
				(pts
					(xy 446.903094 -23.388574) (xy 446.903094 -23.896574) (xy 446.522094 -23.896574) (xy 446.522094 -23.388574)
				)
			)
		)
	)
	(footprint ""
		(layer "B.Cu")
		(at 411.0355 -130.6068 90)
		(property "Reference" "C2M1"
			(at 0 0 90)
			(layer "B.SilkS")
			(hide yes)
			(effects
				(font
					(size 1.27 1.27)
				)
				(justify mirror)
			)
		)
		(property "Value" ""
			(at 0 0 90)
			(layer "B.Fab")
			(effects
				(font
					(size 1.27 1.27)
				)
				(justify mirror)
			)
		)
		(duplicate_pad_numbers_are_jumpers no)
		(fp_poly
			(pts
				(xy 0.4953 -0.2032) (xy -0.4953 -0.2032) (xy -0.4953 1.6002) (xy 0.4953 1.6002)
			)
			(stroke
				(width 0)
				(type default)
			)
			(fill no)
			(layer "B.CrtYd")
		)
		(fp_line
			(start 0.4953 -0.2032)
			(end -0.4953 -0.2032)
			(stroke
				(width 0.1)
				(type default)
			)
			(layer "B.Fab")
		)
		(fp_line
			(start -0.4953 -0.2032)
			(end -0.4953 1.6002)
			(stroke
				(width 0.1)
				(type default)
			)
			(layer "B.Fab")
		)
		(fp_line
			(start 0.4953 1.6002)
			(end 0.4953 -0.2032)
			(stroke
				(width 0.1)
				(type default)
			)
			(layer "B.Fab")
		)
		(fp_line
			(start -0.4953 1.6002)
			(end 0.4953 1.6002)
			(stroke
				(width 0.1)
				(type default)
			)
			(layer "B.Fab")
		)
		(pad "1" smd rect
			(at 0 0 270)
			(size 0.762 0.889)
			(layers "B.Cu" "B.Mask" "B.Paste")
			(net "P1V8_PCH_STBY")
		)
		(pad "2" smd rect
			(at 0 1.397 270)
			(size 0.762 0.889)
			(layers "B.Cu" "B.Mask" "B.Paste")
			(net "GND")
		)
		(zone
			(layer "B.Cu")
			(hatch none 0.5)
			(connect_pads
				(clearance 0)
			)
			(min_thickness 0.25)
			(keepout
				(tracks not_allowed)
				(vias allowed)
				(pads allowed)
				(copperpour not_allowed)
				(footprints allowed)
			)
			(placement
				(enabled no)
				(sheetname "")
			)
			(fill
				(thermal_gap 0.5)
				(thermal_bridge_width 0.5)
				(island_removal_mode 0)
			)
			(polygon
				(pts
					(xy 411.48 -130.9878) (xy 411.48 -130.2258) (xy 411.988 -130.2258) (xy 411.988 -130.9878)
				)
			)
		)
	)
	(footprint ""
		(layer "B.Cu")
		(at 334.01 -150.368 90)
		(property "Reference" "C3L14"
			(at -2.18567 9.525 0)
			(unlocked yes)
			(layer "B.SilkS")
			(effects
				(font
					(size 0.7874 0.5842)
					(thickness 0.1524)
				)
				(justify mirror)
			)
		)
		(property "Value" ""
			(at 0 0 90)
			(layer "B.Fab")
			(effects
				(font
					(size 1.27 1.27)
				)
				(justify mirror)
			)
		)
		(duplicate_pad_numbers_are_jumpers no)
		(fp_line
			(start 2.563114 -1.616456)
			(end 2.563114 1.633728)
			(stroke
				(width 0.1524)
				(type default)
			)
			(layer "B.SilkS")
		)
		(fp_line
			(start 1.6002 -1.616456)
			(end 2.563114 -1.616456)
			(stroke
				(width 0.1524)
				(type default)
			)
			(layer "B.SilkS")
		)
		(fp_line
			(start -1.6002 -1.616456)
			(end -2.504948 -1.616456)
			(stroke
				(width 0.1524)
				(type default)
			)
			(layer "B.SilkS")
		)
		(fp_line
			(start -2.504948 -1.616456)
			(end -2.504948 1.633728)
			(stroke
				(width 0.1524)
				(type default)
			)
			(layer "B.SilkS")
		)
		(fp_line
			(start 2.563114 1.633728)
			(end 1.6002 1.633728)
			(stroke
				(width 0.1524)
				(type default)
			)
			(layer "B.SilkS")
		)
		(fp_line
			(start -2.504948 1.633728)
			(end -1.6002 1.633728)
			(stroke
				(width 0.1524)
				(type default)
			)
			(layer "B.SilkS")
		)
		(fp_line
			(start 2.286 7.366)
			(end 2.286 1.632712)
			(stroke
				(width 0.1524)
				(type default)
			)
			(layer "B.SilkS")
		)
		(fp_line
			(start 2.286 7.366)
			(end 1.60147 7.366)
			(stroke
				(width 0.1524)
				(type default)
			)
			(layer "B.SilkS")
		)
		(fp_line
			(start -2.286 7.366)
			(end -2.286 1.63195)
			(stroke
				(width 0.1524)
				(type default)
			)
			(layer "B.SilkS")
		)
		(fp_line
			(start -2.286 7.366)
			(end -1.600708 7.366)
			(stroke
				(width 0.1524)
				(type default)
			)
			(layer "B.SilkS")
		)
		(fp_rect
			(start 2.286 7.366)
			(end -2.286 -0.254)
			(stroke
				(width 0)
				(type default)
			)
			(fill no)
			(layer "B.CrtYd")
		)
		(fp_line
			(start 2.286 -0.254)
			(end -2.286 -0.254)
			(stroke
				(width 0.1)
				(type default)
			)
			(layer "B.Fab")
		)
		(fp_line
			(start -2.286 -0.254)
			(end -2.286 7.366)
			(stroke
				(width 0.1)
				(type default)
			)
			(layer "B.Fab")
		)
		(fp_line
			(start 2.286 7.366)
			(end 2.286 -0.254)
			(stroke
				(width 0.1)
				(type default)
			)
			(layer "B.Fab")
		)
		(fp_line
			(start -2.286 7.366)
			(end 2.286 7.366)
			(stroke
				(width 0.1)
				(type default)
			)
			(layer "B.Fab")
		)
		(pad "1" smd rect
			(at 0 0 270)
			(size 2.54 3.048)
			(layers "B.Cu" "B.Mask" "B.Paste")
			(net "PVDDQ_DEF")
		)
		(pad "2" smd rect
			(at 0 7.112 270)
			(size 2.54 3.048)
			(layers "B.Cu" "B.Mask" "B.Paste")
			(net "GND")
		)
	)
	(footprint ""
		(layer "B.Cu")
		(at 266.7762 -124.6886 90)
		(property "Reference" "SH4L2"
			(at 0 0 90)
			(layer "B.SilkS")
			(hide yes)
			(effects
				(font
					(size 1.27 1.27)
				)
				(justify mirror)
			)
		)
		(property "Value" ""
			(at 0 0 90)
			(layer "B.Fab")
			(effects
				(font
					(size 1.27 1.27)
				)
				(justify mirror)
			)
		)
		(duplicate_pad_numbers_are_jumpers no)
		(fp_poly
			(pts
				(xy 0.1651 -0.0508) (xy 0.1651 0.5842) (xy -0.1651 0.5842) (xy -0.1651 -0.0508)
			)
			(stroke
				(width 0)
				(type default)
			)
			(fill no)
			(layer "B.CrtYd")
		)
		(fp_line
			(start 0.1651 -0.0508)
			(end -0.1651 -0.0508)
			(stroke
				(width 0.1)
				(type default)
			)
			(layer "B.Fab")
		)
		(fp_line
			(start -0.1651 -0.0508)
			(end -0.1651 0.5842)
			(stroke
				(width 0.1)
				(type default)
			)
			(layer "B.Fab")
		)
		(fp_line
			(start 0.1651 0.5842)
			(end 0.1651 -0.0508)
			(stroke
				(width 0.1)
				(type default)
			)
			(layer "B.Fab")
		)
		(fp_line
			(start -0.1651 0.5842)
			(end 0.1651 0.5842)
			(stroke
				(width 0.1)
				(type default)
			)
			(layer "B.Fab")
		)
		(pad "1" smd custom
			(at 0 0 90)
			(size 0.0762 0.0762)
			(layers "B.Cu" "B.Mask" "B.Paste")
			(net "VSENSE_PVDDQ_DEF_P")
			(options
				(clearance outline)
				(anchor circle)
			)
			(primitives
				(gr_poly
					(pts
						(arc
							(start -0.1524 0.10795)
							(mid -0.098518 0.130268)
							(end -0.0762 0.18415)
						)
						(xy -0.0762 0.22225) (xy 0.0762 0.22225)
						(arc
							(start 0.0762 0.18415)
							(mid 0.098518 0.130268)
							(end 0.1524 0.10795)
						)
						(xy 0.1524 -0.22225) (xy -0.1524 -0.22225)
					)
					(width 0)
					(fill yes)
				)
			)
		)
		(pad "2" smd custom
			(at 0 0.5334 270)
			(size 0.0762 0.0762)
			(layers "B.Cu" "B.Mask" "B.Paste")
			(net "PVDDQ_DEF")
			(options
				(clearance outline)
				(anchor circle)
			)
			(primitives
				(gr_poly
					(pts
						(arc
							(start -0.1524 0.10795)
							(mid -0.098518 0.130268)
							(end -0.0762 0.18415)
						)
						(xy -0.0762 0.22225) (xy 0.0762 0.22225)
						(arc
							(start 0.0762 0.18415)
							(mid 0.098518 0.130268)
							(end 0.1524 0.10795)
						)
						(xy 0.1524 -0.22225) (xy -0.1524 -0.22225)
					)
					(width 0)
					(fill yes)
				)
			)
		)
	)
)
